(kicad_pcb
	(version 20260206)
	(generator "pcbnew")
	(generator_version "10.0")
	(general
		(thickness 1.6)
		(legacy_teardrops no)
	)
	(paper "A4")
	(title_block
		(title "v2-pdb — ms_pdb_v2.brd")
		(comment 1 "Open CloudServer (Microsoft) / footprints 260-269 of 348")
	)
	(layers
		(0 "F.Cu" signal "TOP")
		(4 "In1.Cu" signal "GND")
		(6 "In2.Cu" signal "IN1")
		(8 "In3.Cu" signal "VCC")
		(10 "In4.Cu" signal "VCC1")
		(12 "In5.Cu" signal "IN2")
		(14 "In6.Cu" signal "GND1")
		(2 "B.Cu" signal "BOTTOM")
		(9 "F.Adhes" user "F.Adhesive")
		(11 "B.Adhes" user "B.Adhesive")
		(13 "F.Paste" user "Package Geometry/Pastemask Top")
		(15 "B.Paste" user "Package Geometry/Pastemask Bottom")
		(5 "F.SilkS" user "Ref Des/Silkscreen Top")
		(7 "B.SilkS" user "Ref Des/Silkscreen Bottom")
		(1 "F.Mask" user "Board Geometry/Soldermask Top")
		(3 "B.Mask" user "Board Geometry/Soldermask Bottom")
		(17 "Dwgs.User" user "User.Drawings")
		(19 "Cmts.User" user "User.Comments")
		(21 "Eco1.User" user "User.Eco1")
		(23 "Eco2.User" user "User.Eco2")
		(25 "Edge.Cuts" user "Board Geometry/Outline")
		(27 "Margin" user)
		(31 "F.CrtYd" user "Package Geometry/Place Bound Top")
		(29 "B.CrtYd" user "Package Geometry/Place Bound Bottom")
		(35 "F.Fab" user "Ref Des/Assembly Top")
		(33 "B.Fab" user "Ref Des/Assembly Bottom")
	)
	(footprint ""
		(layer "F.Cu")
		(at 39.90086 -194.114674 180)
		(property "Reference" "R13"
			(at -1.710182 -0.085344 0)
			(unlocked yes)
			(layer "F.SilkS")
			(effects
				(font
					(size 0.7874 0.5842)
					(thickness 0.1524)
				)
				(justify left)
			)
		)
		(property "Value" ""
			(at 0 0 180)
			(layer "F.Fab")
			(effects
				(font
					(size 1.27 1.27)
				)
			)
		)
		(duplicate_pad_numbers_are_jumpers no)
		(fp_line
			(start 0.7874 0.4064)
			(end -0.7874 0.4064)
			(stroke
				(width 0.1524)
				(type default)
			)
			(layer "F.SilkS")
		)
		(fp_line
			(start 0.7874 -0.4064)
			(end 0.7874 0.4064)
			(stroke
				(width 0.1524)
				(type default)
			)
			(layer "F.SilkS")
		)
		(fp_line
			(start -0.7874 0.4064)
			(end -0.7874 -0.4064)
			(stroke
				(width 0.1524)
				(type default)
			)
			(layer "F.SilkS")
		)
		(fp_line
			(start -0.7874 -0.4064)
			(end 0.7874 -0.4064)
			(stroke
				(width 0.1524)
				(type default)
			)
			(layer "F.SilkS")
		)
		(fp_poly
			(pts
				(xy -0.508 0.2794) (xy -0.508 0.2286) (xy -0.635 0.2286) (xy -0.635 -0.254) (xy -0.5334 -0.254)
				(xy -0.5334 -0.2794) (xy 0.5334 -0.2794) (xy 0.5334 -0.254) (xy 0.635 -0.254) (xy 0.635 0.254) (xy 0.5334 0.254)
				(xy 0.5334 0.2794)
			)
			(stroke
				(width 0)
				(type default)
			)
			(fill no)
			(layer "F.CrtYd")
		)
		(pad "1" smd rect
			(at 0.40005 0 180)
			(size 0.4572 0.508)
			(layers "F.Cu" "F.Mask" "F.Paste")
			(net "PSU3_AD0")
		)
		(pad "2" smd rect
			(at -0.40005 0 180)
			(size 0.4572 0.508)
			(layers "F.Cu" "F.Mask" "F.Paste")
			(net "GND")
		)
	)
	(footprint ""
		(layer "F.Cu")
		(at 13.386308 -319.438782 180)
		(property "Reference" "R141"
			(at -1.77546 -0.128016 0)
			(unlocked yes)
			(layer "F.SilkS")
			(effects
				(font
					(size 0.7874 0.5842)
					(thickness 0.1524)
				)
				(justify left)
			)
		)
		(property "Value" ""
			(at 0 0 180)
			(layer "F.Fab")
			(effects
				(font
					(size 1.27 1.27)
				)
			)
		)
		(duplicate_pad_numbers_are_jumpers no)
		(fp_line
			(start 0.7874 0.4064)
			(end -0.7874 0.4064)
			(stroke
				(width 0.1524)
				(type default)
			)
			(layer "F.SilkS")
		)
		(fp_line
			(start 0.7874 -0.4064)
			(end 0.7874 0.4064)
			(stroke
				(width 0.1524)
				(type default)
			)
			(layer "F.SilkS")
		)
		(fp_line
			(start -0.7874 0.4064)
			(end -0.7874 -0.4064)
			(stroke
				(width 0.1524)
				(type default)
			)
			(layer "F.SilkS")
		)
		(fp_line
			(start -0.7874 -0.4064)
			(end 0.7874 -0.4064)
			(stroke
				(width 0.1524)
				(type default)
			)
			(layer "F.SilkS")
		)
		(fp_poly
			(pts
				(xy -0.508 0.2794) (xy -0.508 0.2286) (xy -0.635 0.2286) (xy -0.635 -0.254) (xy -0.5334 -0.254)
				(xy -0.5334 -0.2794) (xy 0.5334 -0.2794) (xy 0.5334 -0.254) (xy 0.635 -0.254) (xy 0.635 0.254) (xy 0.5334 0.254)
				(xy 0.5334 0.2794)
			)
			(stroke
				(width 0)
				(type default)
			)
			(fill no)
			(layer "F.CrtYd")
		)
		(pad "1" smd rect
			(at 0.40005 0 180)
			(size 0.4572 0.508)
			(layers "F.Cu" "F.Mask" "F.Paste")
			(net "FAN_PWM")
		)
		(pad "2" smd rect
			(at -0.40005 0 180)
			(size 0.4572 0.508)
			(layers "F.Cu" "F.Mask" "F.Paste")
			(net "P12V")
		)
	)
	(footprint ""
		(layer "F.Cu")
		(at 27.347672 -107.830366 90)
		(property "Reference" "R117"
			(at -3.30327 -1.060196 90)
			(unlocked yes)
			(layer "F.SilkS")
			(effects
				(font
					(size 0.7874 0.5842)
					(thickness 0.1524)
				)
				(justify left)
			)
		)
		(property "Value" ""
			(at 0 0 90)
			(layer "F.Fab")
			(effects
				(font
					(size 1.27 1.27)
				)
			)
		)
		(duplicate_pad_numbers_are_jumpers no)
		(fp_line
			(start 0.7874 -0.4064)
			(end 0.7874 0.4064)
			(stroke
				(width 0.1524)
				(type default)
			)
			(layer "F.SilkS")
		)
		(fp_line
			(start -0.7874 -0.4064)
			(end 0.7874 -0.4064)
			(stroke
				(width 0.1524)
				(type default)
			)
			(layer "F.SilkS")
		)
		(fp_line
			(start 0.7874 0.4064)
			(end -0.7874 0.4064)
			(stroke
				(width 0.1524)
				(type default)
			)
			(layer "F.SilkS")
		)
		(fp_line
			(start -0.7874 0.4064)
			(end -0.7874 -0.4064)
			(stroke
				(width 0.1524)
				(type default)
			)
			(layer "F.SilkS")
		)
		(fp_poly
			(pts
				(xy -0.508 0.2794) (xy -0.508 0.2286) (xy -0.635 0.2286) (xy -0.635 -0.254) (xy -0.5334 -0.254)
				(xy -0.5334 -0.2794) (xy 0.5334 -0.2794) (xy 0.5334 -0.254) (xy 0.635 -0.254) (xy 0.635 0.254) (xy 0.5334 0.254)
				(xy 0.5334 0.2794)
			)
			(stroke
				(width 0)
				(type default)
			)
			(fill no)
			(layer "F.CrtYd")
		)
		(pad "1" smd rect
			(at 0.40005 0 90)
			(size 0.4572 0.508)
			(layers "F.Cu" "F.Mask" "F.Paste")
			(net "PSU2_REMOTE_N")
		)
		(pad "2" smd rect
			(at -0.40005 0 90)
			(size 0.4572 0.508)
			(layers "F.Cu" "F.Mask" "F.Paste")
			(net "PSU2_REMOTE_R2_N")
		)
	)
	(footprint ""
		(layer "F.Cu")
		(at 69.370956 -197.900544 -90)
		(property "Reference" "C29"
			(at 3.031998 -0.19685 90)
			(unlocked yes)
			(layer "F.SilkS")
			(effects
				(font
					(size 0.7874 0.5842)
					(thickness 0.1524)
				)
			)
		)
		(property "Value" ""
			(at 0 0 270)
			(layer "F.Fab")
			(effects
				(font
					(size 1.27 1.27)
				)
			)
		)
		(duplicate_pad_numbers_are_jumpers no)
		(fp_line
			(start -1.2954 0.5842)
			(end -1.2954 -0.5842)
			(stroke
				(width 0.1524)
				(type default)
			)
			(layer "F.SilkS")
		)
		(fp_line
			(start 1.2954 0.5842)
			(end -1.2954 0.5842)
			(stroke
				(width 0.1524)
				(type default)
			)
			(layer "F.SilkS")
		)
		(fp_line
			(start -1.2954 -0.5842)
			(end 1.2954 -0.5842)
			(stroke
				(width 0.1524)
				(type default)
			)
			(layer "F.SilkS")
		)
		(fp_line
			(start 0 -0.5842)
			(end 0 0.5842)
			(stroke
				(width 0.1524)
				(type default)
			)
			(layer "F.SilkS")
		)
		(fp_line
			(start 1.2954 -0.5842)
			(end 1.2954 0.5842)
			(stroke
				(width 0.1524)
				(type default)
			)
			(layer "F.SilkS")
		)
		(fp_poly
			(pts
				(xy 0.8636 -0.4572) (xy 0.8636 -0.3556) (xy 1.143 -0.3556) (xy 1.143 0.3556) (xy 0.8636 0.3556)
				(xy 0.8636 0.4572) (xy -0.8636 0.4572) (xy -0.8636 0.3556) (xy -1.143 0.3556) (xy -1.143 -0.3556)
				(xy -0.8636 -0.3556) (xy -0.8636 -0.4572)
			)
			(stroke
				(width 0)
				(type default)
			)
			(fill no)
			(layer "F.CrtYd")
		)
		(fp_line
			(start -0.884936 0.504952)
			(end -0.884936 -0.504952)
			(stroke
				(width 0.1)
				(type default)
			)
			(layer "F.Fab")
		)
		(fp_line
			(start 0.884936 0.504952)
			(end -0.884936 0.504952)
			(stroke
				(width 0.1)
				(type default)
			)
			(layer "F.Fab")
		)
		(fp_line
			(start -0.884936 -0.504952)
			(end 0.884936 -0.504952)
			(stroke
				(width 0.1)
				(type default)
			)
			(layer "F.Fab")
		)
		(fp_line
			(start 0.884936 -0.504952)
			(end 0.884936 0.504952)
			(stroke
				(width 0.1)
				(type default)
			)
			(layer "F.Fab")
		)
		(pad "1" smd rect
			(at 0.7366 0)
			(size 0.7112 0.8128)
			(layers "F.Cu" "F.Mask" "F.Paste")
			(net "P12V")
		)
		(pad "2" smd rect
			(at -0.7366 0)
			(size 0.7112 0.8128)
			(layers "F.Cu" "F.Mask" "F.Paste")
			(net "GND")
		)
	)
	(footprint ""
		(layer "F.Cu")
		(at 46.40834 -243.096034 180)
		(property "Reference" "R92"
			(at 4.252722 -0.212598 0)
			(unlocked yes)
			(layer "F.SilkS")
			(effects
				(font
					(size 0.7874 0.5842)
					(thickness 0.1524)
				)
				(justify left)
			)
		)
		(property "Value" ""
			(at 0 0 180)
			(layer "F.Fab")
			(effects
				(font
					(size 1.27 1.27)
				)
			)
		)
		(duplicate_pad_numbers_are_jumpers no)
		(fp_line
			(start 0.7874 0.4064)
			(end -0.7874 0.4064)
			(stroke
				(width 0.1524)
				(type default)
			)
			(layer "F.SilkS")
		)
		(fp_line
			(start 0.7874 -0.4064)
			(end 0.7874 0.4064)
			(stroke
				(width 0.1524)
				(type default)
			)
			(layer "F.SilkS")
		)
		(fp_line
			(start -0.7874 0.4064)
			(end -0.7874 -0.4064)
			(stroke
				(width 0.1524)
				(type default)
			)
			(layer "F.SilkS")
		)
		(fp_line
			(start -0.7874 -0.4064)
			(end 0.7874 -0.4064)
			(stroke
				(width 0.1524)
				(type default)
			)
			(layer "F.SilkS")
		)
		(fp_poly
			(pts
				(xy -0.508 0.2794) (xy -0.508 0.2286) (xy -0.635 0.2286) (xy -0.635 -0.254) (xy -0.5334 -0.254)
				(xy -0.5334 -0.2794) (xy 0.5334 -0.2794) (xy 0.5334 -0.254) (xy 0.635 -0.254) (xy 0.635 0.254) (xy 0.5334 0.254)
				(xy 0.5334 0.2794)
			)
			(stroke
				(width 0)
				(type default)
			)
			(fill no)
			(layer "F.CrtYd")
		)
		(pad "1" smd rect
			(at 0.40005 0 180)
			(size 0.4572 0.508)
			(layers "F.Cu" "F.Mask" "F.Paste")
			(net "PSU2_REMOTE_R_P")
		)
		(pad "2" smd rect
			(at -0.40005 0 180)
			(size 0.4572 0.508)
			(layers "F.Cu" "F.Mask" "F.Paste")
			(net "P12V")
		)
	)
	(footprint ""
		(layer "F.Cu")
		(at 26.18613 -190.368174)
		(property "Reference" "R136"
			(at -4.256532 0.268224 0)
			(unlocked yes)
			(layer "F.SilkS")
			(effects
				(font
					(size 0.7874 0.5842)
					(thickness 0.1524)
				)
				(justify left)
			)
		)
		(property "Value" ""
			(at 0 0 0)
			(layer "F.Fab")
			(effects
				(font
					(size 1.27 1.27)
				)
			)
		)
		(duplicate_pad_numbers_are_jumpers no)
		(fp_line
			(start -0.7874 -0.4064)
			(end 0.7874 -0.4064)
			(stroke
				(width 0.1524)
				(type default)
			)
			(layer "F.SilkS")
		)
		(fp_line
			(start -0.7874 0.4064)
			(end -0.7874 -0.4064)
			(stroke
				(width 0.1524)
				(type default)
			)
			(layer "F.SilkS")
		)
		(fp_line
			(start 0.7874 -0.4064)
			(end 0.7874 0.4064)
			(stroke
				(width 0.1524)
				(type default)
			)
			(layer "F.SilkS")
		)
		(fp_line
			(start 0.7874 0.4064)
			(end -0.7874 0.4064)
			(stroke
				(width 0.1524)
				(type default)
			)
			(layer "F.SilkS")
		)
		(fp_poly
			(pts
				(xy -0.508 0.2794) (xy -0.508 0.2286) (xy -0.635 0.2286) (xy -0.635 -0.254) (xy -0.5334 -0.254)
				(xy -0.5334 -0.2794) (xy 0.5334 -0.2794) (xy 0.5334 -0.254) (xy 0.635 -0.254) (xy 0.635 0.254) (xy 0.5334 0.254)
				(xy 0.5334 0.2794)
			)
			(stroke
				(width 0)
				(type default)
			)
			(fill no)
			(layer "F.CrtYd")
		)
		(pad "1" smd rect
			(at 0.40005 0)
			(size 0.4572 0.508)
			(layers "F.Cu" "F.Mask" "F.Paste")
			(net "PSU3_CSAHRE")
		)
		(pad "2" smd rect
			(at -0.40005 0)
			(size 0.4572 0.508)
			(layers "F.Cu" "F.Mask" "F.Paste")
			(net "PSU_CSAHRE")
		)
	)
	(footprint ""
		(layer "F.Cu")
		(at 70.658736 -197.392544 -90)
		(property "Reference" "C30"
			(at 3.603498 -0.19812 90)
			(unlocked yes)
			(layer "F.SilkS")
			(effects
				(font
					(size 0.7874 0.5842)
					(thickness 0.1524)
				)
				(justify left)
			)
		)
		(property "Value" ""
			(at 0 0 270)
			(layer "F.Fab")
			(effects
				(font
					(size 1.27 1.27)
				)
			)
		)
		(duplicate_pad_numbers_are_jumpers no)
		(fp_line
			(start -0.7874 0.4064)
			(end -0.7874 -0.4064)
			(stroke
				(width 0.1524)
				(type default)
			)
			(layer "F.SilkS")
		)
		(fp_line
			(start 0.7874 0.4064)
			(end -0.7874 0.4064)
			(stroke
				(width 0.1524)
				(type default)
			)
			(layer "F.SilkS")
		)
		(fp_line
			(start 0 0.381)
			(end 0 -0.381)
			(stroke
				(width 0.1524)
				(type default)
			)
			(layer "F.SilkS")
		)
		(fp_line
			(start -0.7874 -0.4064)
			(end 0.7874 -0.4064)
			(stroke
				(width 0.1524)
				(type default)
			)
			(layer "F.SilkS")
		)
		(fp_line
			(start 0.7874 -0.4064)
			(end 0.7874 0.4064)
			(stroke
				(width 0.1524)
				(type default)
			)
			(layer "F.SilkS")
		)
		(fp_poly
			(pts
				(xy -0.5334 0.254) (xy -0.635 0.254) (xy -0.635 0.2286) (xy -0.635 -0.254) (xy -0.5334 -0.254) (xy -0.5334 -0.2794)
				(xy 0.5334 -0.2794) (xy 0.5334 -0.254) (xy 0.635 -0.254) (xy 0.635 0.254) (xy 0.5334 0.254) (xy 0.5334 0.2794)
				(xy -0.508 0.2794) (xy -0.5334 0.2794)
			)
			(stroke
				(width 0)
				(type default)
			)
			(fill no)
			(layer "F.CrtYd")
		)
		(pad "1" smd rect
			(at 0.40005 0 270)
			(size 0.4572 0.508)
			(layers "F.Cu" "F.Mask" "F.Paste")
			(net "P12V")
		)
		(pad "2" smd rect
			(at -0.40005 0 270)
			(size 0.4572 0.508)
			(layers "F.Cu" "F.Mask" "F.Paste")
			(net "GND")
		)
	)
	(footprint ""
		(layer "F.Cu")
		(at 67.867276 -304.009806 90)
		(property "Reference" "C55"
			(at 1.053846 0.04826 90)
			(unlocked yes)
			(layer "F.SilkS")
			(effects
				(font
					(size 0.7874 0.5842)
					(thickness 0.1524)
				)
				(justify left)
			)
		)
		(property "Value" ""
			(at 0 0 90)
			(layer "F.Fab")
			(effects
				(font
					(size 1.27 1.27)
				)
			)
		)
		(duplicate_pad_numbers_are_jumpers no)
		(fp_line
			(start 0.7874 -0.4064)
			(end 0.7874 0.4064)
			(stroke
				(width 0.1524)
				(type default)
			)
			(layer "F.SilkS")
		)
		(fp_line
			(start -0.7874 -0.4064)
			(end 0.7874 -0.4064)
			(stroke
				(width 0.1524)
				(type default)
			)
			(layer "F.SilkS")
		)
		(fp_line
			(start 0 0.381)
			(end 0 -0.381)
			(stroke
				(width 0.1524)
				(type default)
			)
			(layer "F.SilkS")
		)
		(fp_line
			(start 0.7874 0.4064)
			(end -0.7874 0.4064)
			(stroke
				(width 0.1524)
				(type default)
			)
			(layer "F.SilkS")
		)
		(fp_line
			(start -0.7874 0.4064)
			(end -0.7874 -0.4064)
			(stroke
				(width 0.1524)
				(type default)
			)
			(layer "F.SilkS")
		)
		(fp_poly
			(pts
				(xy -0.5334 0.254) (xy -0.635 0.254) (xy -0.635 0.2286) (xy -0.635 -0.254) (xy -0.5334 -0.254) (xy -0.5334 -0.2794)
				(xy 0.5334 -0.2794) (xy 0.5334 -0.254) (xy 0.635 -0.254) (xy 0.635 0.254) (xy 0.5334 0.254) (xy 0.5334 0.2794)
				(xy -0.508 0.2794) (xy -0.5334 0.2794)
			)
			(stroke
				(width 0)
				(type default)
			)
			(fill no)
			(layer "F.CrtYd")
		)
		(pad "1" smd rect
			(at 0.40005 0 90)
			(size 0.4572 0.508)
			(layers "F.Cu" "F.Mask" "F.Paste")
			(net "P12V")
		)
		(pad "2" smd rect
			(at -0.40005 0 90)
			(size 0.4572 0.508)
			(layers "F.Cu" "F.Mask" "F.Paste")
			(net "GND")
		)
	)
	(footprint ""
		(layer "F.Cu")
		(at 98.702114 -15.774924)
		(property "Reference" ""
			(at 0 0 0)
			(layer "F.SilkS")
			(hide yes)
			(effects
				(font
					(size 1.27 1.27)
				)
			)
		)
		(property "Value" ""
			(at 0 0 0)
			(layer "F.Fab")
			(effects
				(font
					(size 1.27 1.27)
				)
			)
		)
		(duplicate_pad_numbers_are_jumpers no)
		(fp_poly
			(pts
				(arc
					(start 1.4986 0)
					(mid -1.4986 0)
					(end 1.4986 0)
				)
			)
			(stroke
				(width 0)
				(type default)
			)
			(fill no)
			(layer "F.CrtYd")
		)
		(pad "1" smd circle
			(at 0 0)
			(size 0.9906 0.9906)
			(layers "F.Cu" "F.Mask" "F.Paste")
			(net "Net_223")
		)
		(zone
			(layer "F.Cu")
			(hatch none 0.5)
			(connect_pads
				(clearance 0)
			)
			(min_thickness 0.25)
			(keepout
				(tracks not_allowed)
				(vias allowed)
				(pads allowed)
				(copperpour not_allowed)
				(footprints allowed)
			)
			(placement
				(enabled no)
				(sheetname "")
			)
			(fill
				(thermal_gap 0.5)
				(thermal_bridge_width 0.5)
				(island_removal_mode 0)
			)
			(polygon
				(pts
					(arc
						(start 100.327714 -15.774924)
						(mid 97.076514 -15.774924)
						(end 100.327714 -15.774924)
					)
				)
			)
		)
	)
	(footprint ""
		(layer "F.Cu")
		(at 69.44487 -127.633476 90)
		(property "Reference" "C26"
			(at 1.175512 -0.0254 90)
			(unlocked yes)
			(layer "F.SilkS")
			(effects
				(font
					(size 0.7874 0.5842)
					(thickness 0.1524)
				)
				(justify left)
			)
		)
		(property "Value" ""
			(at 0 0 90)
			(layer "F.Fab")
			(effects
				(font
					(size 1.27 1.27)
				)
			)
		)
		(duplicate_pad_numbers_are_jumpers no)
		(fp_line
			(start 0.7874 -0.4064)
			(end 0.7874 0.4064)
			(stroke
				(width 0.1524)
				(type default)
			)
			(layer "F.SilkS")
		)
		(fp_line
			(start -0.7874 -0.4064)
			(end 0.7874 -0.4064)
			(stroke
				(width 0.1524)
				(type default)
			)
			(layer "F.SilkS")
		)
		(fp_line
			(start 0 0.381)
			(end 0 -0.381)
			(stroke
				(width 0.1524)
				(type default)
			)
			(layer "F.SilkS")
		)
		(fp_line
			(start 0.7874 0.4064)
			(end -0.7874 0.4064)
			(stroke
				(width 0.1524)
				(type default)
			)
			(layer "F.SilkS")
		)
		(fp_line
			(start -0.7874 0.4064)
			(end -0.7874 -0.4064)
			(stroke
				(width 0.1524)
				(type default)
			)
			(layer "F.SilkS")
		)
		(fp_poly
			(pts
				(xy -0.5334 0.254) (xy -0.635 0.254) (xy -0.635 0.2286) (xy -0.635 -0.254) (xy -0.5334 -0.254) (xy -0.5334 -0.2794)
				(xy 0.5334 -0.2794) (xy 0.5334 -0.254) (xy 0.635 -0.254) (xy 0.635 0.254) (xy 0.5334 0.254) (xy 0.5334 0.2794)
				(xy -0.508 0.2794) (xy -0.5334 0.2794)
			)
			(stroke
				(width 0)
				(type default)
			)
			(fill no)
			(layer "F.CrtYd")
		)
		(pad "1" smd rect
			(at 0.40005 0 90)
			(size 0.4572 0.508)
			(layers "F.Cu" "F.Mask" "F.Paste")
			(net "P12V")
		)
		(pad "2" smd rect
			(at -0.40005 0 90)
			(size 0.4572 0.508)
			(layers "F.Cu" "F.Mask" "F.Paste")
			(net "GND")
		)
	)
)
